(kicad_pcb
	(version 20260206)
	(generator "pcbnew")
	(generator_version "10.0")
	(general
		(thickness 1.6)
		(legacy_teardrops no)
	)
	(paper "A4")
	(title_block
		(title "01162023_DA0F0TEBIF0_F0T_Expander_BD_F_brd_V02_OCP.brd")
		(comment 1 "Grand Teton / footprints 8405-8415 of 9728")
	)
	(layers
		(0 "F.Cu" signal "TOP")
		(4 "In1.Cu" signal "GND")
		(6 "In2.Cu" signal "VCC")
		(8 "In3.Cu" signal "VCC1")
		(10 "In4.Cu" signal "GND1")
		(12 "In5.Cu" signal "IN1")
		(14 "In6.Cu" signal "GND2")
		(16 "In7.Cu" signal "IN2")
		(18 "In8.Cu" signal "GND3")
		(20 "In9.Cu" signal "IN3")
		(22 "In10.Cu" signal "GND4")
		(24 "In11.Cu" signal "IN4")
		(26 "In12.Cu" signal "GND5")
		(28 "In13.Cu" signal "IN5")
		(30 "In14.Cu" signal "GND6")
		(32 "In15.Cu" signal "IN6")
		(34 "In16.Cu" signal "GND7")
		(2 "B.Cu" signal "BOTTOM")
		(9 "F.Adhes" user "F.Adhesive")
		(11 "B.Adhes" user "B.Adhesive")
		(13 "F.Paste" user "Package Geometry/Pastemask Top")
		(15 "B.Paste" user "Package Geometry/Pastemask Bottom")
		(5 "F.SilkS" user "Ref Des/Silkscreen Top")
		(7 "B.SilkS" user "Ref Des/Silkscreen Bottom")
		(1 "F.Mask" user "Board Geometry/Soldermask Top")
		(3 "B.Mask" user "Board Geometry/Soldermask Bottom")
		(17 "Dwgs.User" user "User.Drawings")
		(19 "Cmts.User" user "User.Comments")
		(21 "Eco1.User" user "User.Eco1")
		(23 "Eco2.User" user "User.Eco2")
		(25 "Edge.Cuts" user "Board Geometry/Outline")
		(27 "Margin" user)
		(31 "F.CrtYd" user "Package Geometry/Place Bound Top")
		(29 "B.CrtYd" user "Package Geometry/Place Bound Bottom")
		(35 "F.Fab" user "Ref Des/Assembly Top")
		(33 "B.Fab" user "Ref Des/Assembly Bottom")
	)
	(footprint ""
		(layer "B.Cu")
		(at 293.120318 -200.261474 180)
		(property "Reference" "C2110"
			(at 0 0 0)
			(layer "B.SilkS")
			(hide yes)
			(effects
				(font
					(size 1.27 1.27)
				)
				(justify mirror)
			)
		)
		(property "Value" ""
			(at 0 0 0)
			(layer "B.Fab")
			(effects
				(font
					(size 1.27 1.27)
				)
				(justify mirror)
			)
		)
		(duplicate_pad_numbers_are_jumpers no)
		(fp_line
			(start 0.7874 0.4064)
			(end 0.7874 -0.4064)
			(stroke
				(width 0.1524)
				(type default)
			)
			(layer "B.SilkS")
		)
		(fp_line
			(start 0.7874 -0.4064)
			(end -0.7874 -0.4064)
			(stroke
				(width 0.1524)
				(type default)
			)
			(layer "B.SilkS")
		)
		(fp_line
			(start -0.7874 0.4064)
			(end 0.7874 0.4064)
			(stroke
				(width 0.1524)
				(type default)
			)
			(layer "B.SilkS")
		)
		(fp_line
			(start -0.7874 -0.4064)
			(end -0.7874 0.4064)
			(stroke
				(width 0.1524)
				(type default)
			)
			(layer "B.SilkS")
		)
		(fp_line
			(start 0.67945 0.3048)
			(end 0.67945 -0.305054)
			(stroke
				(width 0.1)
				(type default)
			)
			(layer "B.Fab")
		)
		(fp_line
			(start 0.67945 -0.305054)
			(end 0.12065 -0.305054)
			(stroke
				(width 0.1)
				(type default)
			)
			(layer "B.Fab")
		)
		(fp_line
			(start 0.12065 0.3048)
			(end 0.67945 0.3048)
			(stroke
				(width 0.1)
				(type default)
			)
			(layer "B.Fab")
		)
		(fp_line
			(start 0.12065 0.2794)
			(end 0.12065 0.3048)
			(stroke
				(width 0.1)
				(type default)
			)
			(layer "B.Fab")
		)
		(fp_line
			(start 0.12065 -0.2794)
			(end -0.12065 -0.2794)
			(stroke
				(width 0.1)
				(type default)
			)
			(layer "B.Fab")
		)
		(fp_line
			(start 0.12065 -0.305054)
			(end 0.12065 -0.2794)
			(stroke
				(width 0.1)
				(type default)
			)
			(layer "B.Fab")
		)
		(fp_line
			(start -0.120396 0.3048)
			(end -0.120396 0.2794)
			(stroke
				(width 0.1)
				(type default)
			)
			(layer "B.Fab")
		)
		(fp_line
			(start -0.120396 0.2794)
			(end 0.12065 0.2794)
			(stroke
				(width 0.1)
				(type default)
			)
			(layer "B.Fab")
		)
		(fp_line
			(start -0.12065 -0.2794)
			(end -0.12065 -0.3048)
			(stroke
				(width 0.1)
				(type default)
			)
			(layer "B.Fab")
		)
		(fp_line
			(start -0.12065 -0.3048)
			(end -0.67945 -0.3048)
			(stroke
				(width 0.1)
				(type default)
			)
			(layer "B.Fab")
		)
		(fp_line
			(start -0.67945 0.3048)
			(end -0.120396 0.3048)
			(stroke
				(width 0.1)
				(type default)
			)
			(layer "B.Fab")
		)
		(fp_line
			(start -0.67945 -0.3048)
			(end -0.67945 0.3048)
			(stroke
				(width 0.1)
				(type default)
			)
			(layer "B.Fab")
		)
		(pad "1" smd circle
			(at 0.40005 0)
			(size 0 0)
			(layers "B.Cu" "B.Mask" "B.Paste")
			(net "GND")
		)
		(pad "2" smd circle
			(at -0.40005 0)
			(size 0 0)
			(layers "B.Cu" "B.Mask" "B.Paste")
			(net "P3V3_AUX")
		)
	)
	(footprint ""
		(layer "B.Cu")
		(at 280.924762 -293.99992 90)
		(property "Reference" "C1638"
			(at 0 0 90)
			(layer "B.SilkS")
			(hide yes)
			(effects
				(font
					(size 1.27 1.27)
				)
				(justify mirror)
			)
		)
		(property "Value" ""
			(at 0 0 90)
			(layer "B.Fab")
			(effects
				(font
					(size 1.27 1.27)
				)
				(justify mirror)
			)
		)
		(duplicate_pad_numbers_are_jumpers no)
		(fp_line
			(start 0.299974 -0.150114)
			(end -0.299974 -0.150114)
			(stroke
				(width 0.1)
				(type default)
			)
			(layer "B.Fab")
		)
		(fp_line
			(start -0.299974 -0.150114)
			(end -0.299974 0.150114)
			(stroke
				(width 0.1)
				(type default)
			)
			(layer "B.Fab")
		)
		(fp_line
			(start 0.299974 0.150114)
			(end 0.299974 -0.150114)
			(stroke
				(width 0.1)
				(type default)
			)
			(layer "B.Fab")
		)
		(fp_line
			(start -0.299974 0.150114)
			(end 0.299974 0.150114)
			(stroke
				(width 0.1)
				(type default)
			)
			(layer "B.Fab")
		)
		(pad "1" smd rect
			(at 0.2667 0 270)
			(size 0.3048 0.381)
			(layers "B.Cu" "B.Mask" "B.Paste")
			(net "P0V8_PEX2")
		)
		(pad "2" smd rect
			(at -0.2667 0 270)
			(size 0.3048 0.381)
			(layers "B.Cu" "B.Mask" "B.Paste")
			(net "GND")
		)
	)
	(footprint ""
		(layer "B.Cu")
		(at 287.099756 -292.099746 90)
		(property "Reference" "C1743"
			(at 0 0 90)
			(layer "B.SilkS")
			(hide yes)
			(effects
				(font
					(size 1.27 1.27)
				)
				(justify mirror)
			)
		)
		(property "Value" ""
			(at 0 0 90)
			(layer "B.Fab")
			(effects
				(font
					(size 1.27 1.27)
				)
				(justify mirror)
			)
		)
		(duplicate_pad_numbers_are_jumpers no)
		(fp_line
			(start 0.299974 -0.150114)
			(end -0.299974 -0.150114)
			(stroke
				(width 0.1)
				(type default)
			)
			(layer "B.Fab")
		)
		(fp_line
			(start -0.299974 -0.150114)
			(end -0.299974 0.150114)
			(stroke
				(width 0.1)
				(type default)
			)
			(layer "B.Fab")
		)
		(fp_line
			(start 0.299974 0.150114)
			(end 0.299974 -0.150114)
			(stroke
				(width 0.1)
				(type default)
			)
			(layer "B.Fab")
		)
		(fp_line
			(start -0.299974 0.150114)
			(end 0.299974 0.150114)
			(stroke
				(width 0.1)
				(type default)
			)
			(layer "B.Fab")
		)
		(pad "1" smd rect
			(at 0.2667 0 270)
			(size 0.3048 0.381)
			(layers "B.Cu" "B.Mask" "B.Paste")
			(net "P0V8_SERDES_VDDA_PEX2")
		)
		(pad "2" smd rect
			(at -0.2667 0 270)
			(size 0.3048 0.381)
			(layers "B.Cu" "B.Mask" "B.Paste")
			(net "GND")
		)
	)
	(footprint ""
		(layer "B.Cu")
		(at 49.5554 -150.9776)
		(property "Reference" "R20"
			(at 0 0 0)
			(layer "B.SilkS")
			(hide yes)
			(effects
				(font
					(size 1.27 1.27)
				)
				(justify mirror)
			)
		)
		(property "Value" ""
			(at 0 0 0)
			(layer "B.Fab")
			(effects
				(font
					(size 1.27 1.27)
				)
				(justify mirror)
			)
		)
		(duplicate_pad_numbers_are_jumpers no)
		(fp_line
			(start -0.7874 -0.4064)
			(end -0.7874 0.4064)
			(stroke
				(width 0.1524)
				(type default)
			)
			(layer "B.SilkS")
		)
		(fp_line
			(start -0.7874 0.4064)
			(end 0.7874 0.4064)
			(stroke
				(width 0.1524)
				(type default)
			)
			(layer "B.SilkS")
		)
		(fp_line
			(start 0.7874 -0.4064)
			(end -0.7874 -0.4064)
			(stroke
				(width 0.1524)
				(type default)
			)
			(layer "B.SilkS")
		)
		(fp_line
			(start 0.7874 0.4064)
			(end 0.7874 -0.4064)
			(stroke
				(width 0.1524)
				(type default)
			)
			(layer "B.SilkS")
		)
		(fp_line
			(start -0.67945 -0.3048)
			(end -0.67945 0.3048)
			(stroke
				(width 0.1)
				(type default)
			)
			(layer "B.Fab")
		)
		(fp_line
			(start -0.67945 0.3048)
			(end -0.120396 0.3048)
			(stroke
				(width 0.1)
				(type default)
			)
			(layer "B.Fab")
		)
		(fp_line
			(start -0.12065 -0.3048)
			(end -0.67945 -0.3048)
			(stroke
				(width 0.1)
				(type default)
			)
			(layer "B.Fab")
		)
		(fp_line
			(start -0.12065 -0.2794)
			(end -0.12065 -0.3048)
			(stroke
				(width 0.1)
				(type default)
			)
			(layer "B.Fab")
		)
		(fp_line
			(start -0.120396 0.2794)
			(end 0.12065 0.2794)
			(stroke
				(width 0.1)
				(type default)
			)
			(layer "B.Fab")
		)
		(fp_line
			(start -0.120396 0.3048)
			(end -0.120396 0.2794)
			(stroke
				(width 0.1)
				(type default)
			)
			(layer "B.Fab")
		)
		(fp_line
			(start 0.12065 -0.305054)
			(end 0.12065 -0.2794)
			(stroke
				(width 0.1)
				(type default)
			)
			(layer "B.Fab")
		)
		(fp_line
			(start 0.12065 -0.2794)
			(end -0.12065 -0.2794)
			(stroke
				(width 0.1)
				(type default)
			)
			(layer "B.Fab")
		)
		(fp_line
			(start 0.12065 0.2794)
			(end 0.12065 0.3048)
			(stroke
				(width 0.1)
				(type default)
			)
			(layer "B.Fab")
		)
		(fp_line
			(start 0.12065 0.3048)
			(end 0.67945 0.3048)
			(stroke
				(width 0.1)
				(type default)
			)
			(layer "B.Fab")
		)
		(fp_line
			(start 0.67945 -0.305054)
			(end 0.12065 -0.305054)
			(stroke
				(width 0.1)
				(type default)
			)
			(layer "B.Fab")
		)
		(fp_line
			(start 0.67945 0.3048)
			(end 0.67945 -0.305054)
			(stroke
				(width 0.1)
				(type default)
			)
			(layer "B.Fab")
		)
		(pad "1" smd circle
			(at 0.40005 0 180)
			(size 0 0)
			(layers "B.Cu" "B.Mask" "B.Paste")
			(net "CLK_50M_NIC0_RBT_REF")
		)
		(pad "2" smd circle
			(at -0.40005 0 180)
			(size 0 0)
			(layers "B.Cu" "B.Mask" "B.Paste")
			(net "GND")
		)
	)
	(footprint ""
		(layer "B.Cu")
		(at 300.607984 -299.224954 180)
		(property "Reference" "C1704"
			(at 0 0 0)
			(layer "B.SilkS")
			(hide yes)
			(effects
				(font
					(size 1.27 1.27)
				)
				(justify mirror)
			)
		)
		(property "Value" ""
			(at 0 0 0)
			(layer "B.Fab")
			(effects
				(font
					(size 1.27 1.27)
				)
				(justify mirror)
			)
		)
		(duplicate_pad_numbers_are_jumpers no)
		(fp_line
			(start 0.299974 0.150114)
			(end 0.299974 -0.150114)
			(stroke
				(width 0.1)
				(type default)
			)
			(layer "B.Fab")
		)
		(fp_line
			(start 0.299974 -0.150114)
			(end -0.299974 -0.150114)
			(stroke
				(width 0.1)
				(type default)
			)
			(layer "B.Fab")
		)
		(fp_line
			(start -0.299974 0.150114)
			(end 0.299974 0.150114)
			(stroke
				(width 0.1)
				(type default)
			)
			(layer "B.Fab")
		)
		(fp_line
			(start -0.299974 -0.150114)
			(end -0.299974 0.150114)
			(stroke
				(width 0.1)
				(type default)
			)
			(layer "B.Fab")
		)
		(pad "1" smd rect
			(at 0.2667 0)
			(size 0.3048 0.381)
			(layers "B.Cu" "B.Mask" "B.Paste")
			(net "P0V8_SERDES_VDDA_PEX2")
		)
		(pad "2" smd rect
			(at -0.2667 0)
			(size 0.3048 0.381)
			(layers "B.Cu" "B.Mask" "B.Paste")
			(net "GND")
		)
	)
	(footprint ""
		(layer "B.Cu")
		(at 52.524914 -293.99992 90)
		(property "Reference" "C1134"
			(at 0 0 90)
			(layer "B.SilkS")
			(hide yes)
			(effects
				(font
					(size 1.27 1.27)
				)
				(justify mirror)
			)
		)
		(property "Value" ""
			(at 0 0 90)
			(layer "B.Fab")
			(effects
				(font
					(size 1.27 1.27)
				)
				(justify mirror)
			)
		)
		(duplicate_pad_numbers_are_jumpers no)
		(fp_line
			(start 0.299974 -0.150114)
			(end -0.299974 -0.150114)
			(stroke
				(width 0.1)
				(type default)
			)
			(layer "B.Fab")
		)
		(fp_line
			(start -0.299974 -0.150114)
			(end -0.299974 0.150114)
			(stroke
				(width 0.1)
				(type default)
			)
			(layer "B.Fab")
		)
		(fp_line
			(start 0.299974 0.150114)
			(end 0.299974 -0.150114)
			(stroke
				(width 0.1)
				(type default)
			)
			(layer "B.Fab")
		)
		(fp_line
			(start -0.299974 0.150114)
			(end 0.299974 0.150114)
			(stroke
				(width 0.1)
				(type default)
			)
			(layer "B.Fab")
		)
		(pad "1" smd rect
			(at 0.2667 0 270)
			(size 0.3048 0.381)
			(layers "B.Cu" "B.Mask" "B.Paste")
			(net "P0V8_PEX0")
		)
		(pad "2" smd rect
			(at -0.2667 0 270)
			(size 0.3048 0.381)
			(layers "B.Cu" "B.Mask" "B.Paste")
			(net "GND")
		)
	)
	(footprint ""
		(layer "B.Cu")
		(at 50.57013 -305.399948 -90)
		(property "Reference" "C2984"
			(at 0 0 90)
			(layer "B.SilkS")
			(hide yes)
			(effects
				(font
					(size 1.27 1.27)
				)
				(justify mirror)
			)
		)
		(property "Value" ""
			(at 0 0 90)
			(layer "B.Fab")
			(effects
				(font
					(size 1.27 1.27)
				)
				(justify mirror)
			)
		)
		(duplicate_pad_numbers_are_jumpers no)
		(fp_line
			(start -0.299974 0.150114)
			(end 0.299974 0.150114)
			(stroke
				(width 0.1)
				(type default)
			)
			(layer "B.Fab")
		)
		(fp_line
			(start 0.299974 0.150114)
			(end 0.299974 -0.150114)
			(stroke
				(width 0.1)
				(type default)
			)
			(layer "B.Fab")
		)
		(fp_line
			(start -0.299974 -0.150114)
			(end -0.299974 0.150114)
			(stroke
				(width 0.1)
				(type default)
			)
			(layer "B.Fab")
		)
		(fp_line
			(start 0.299974 -0.150114)
			(end -0.299974 -0.150114)
			(stroke
				(width 0.1)
				(type default)
			)
			(layer "B.Fab")
		)
		(pad "1" smd rect
			(at 0.2667 0 90)
			(size 0.3048 0.381)
			(layers "B.Cu" "B.Mask" "B.Paste")
			(net "P1V25_SERDES_VDDPLL_PEX0")
		)
		(pad "2" smd rect
			(at -0.2667 0 90)
			(size 0.3048 0.381)
			(layers "B.Cu" "B.Mask" "B.Paste")
			(net "GND")
		)
	)
	(footprint ""
		(layer "B.Cu")
		(at 73.400158 -110.115096)
		(property "Reference" "C865"
			(at 0 0 0)
			(layer "B.SilkS")
			(hide yes)
			(effects
				(font
					(size 1.27 1.27)
				)
				(justify mirror)
			)
		)
		(property "Value" ""
			(at 0 0 0)
			(layer "B.Fab")
			(effects
				(font
					(size 1.27 1.27)
				)
				(justify mirror)
			)
		)
		(duplicate_pad_numbers_are_jumpers no)
		(fp_line
			(start -0.299974 -0.150114)
			(end -0.299974 0.150114)
			(stroke
				(width 0.1)
				(type default)
			)
			(layer "B.Fab")
		)
		(fp_line
			(start -0.299974 0.150114)
			(end 0.299974 0.150114)
			(stroke
				(width 0.1)
				(type default)
			)
			(layer "B.Fab")
		)
		(fp_line
			(start 0.299974 -0.150114)
			(end -0.299974 -0.150114)
			(stroke
				(width 0.1)
				(type default)
			)
			(layer "B.Fab")
		)
		(fp_line
			(start 0.299974 0.150114)
			(end 0.299974 -0.150114)
			(stroke
				(width 0.1)
				(type default)
			)
			(layer "B.Fab")
		)
		(pad "1" smd rect
			(at 0.2667 0 180)
			(size 0.3048 0.381)
			(layers "B.Cu" "B.Mask" "B.Paste")
			(net "P12V_NIC1")
		)
		(pad "2" smd rect
			(at -0.2667 0 180)
			(size 0.3048 0.381)
			(layers "B.Cu" "B.Mask" "B.Paste")
			(net "GND")
		)
	)
	(footprint ""
		(layer "B.Cu")
		(at 295.649904 -301.599854 -90)
		(property "Reference" "C1740"
			(at 0 0 90)
			(layer "B.SilkS")
			(hide yes)
			(effects
				(font
					(size 1.27 1.27)
				)
				(justify mirror)
			)
		)
		(property "Value" ""
			(at 0 0 90)
			(layer "B.Fab")
			(effects
				(font
					(size 1.27 1.27)
				)
				(justify mirror)
			)
		)
		(duplicate_pad_numbers_are_jumpers no)
		(fp_line
			(start -0.299974 0.150114)
			(end 0.299974 0.150114)
			(stroke
				(width 0.1)
				(type default)
			)
			(layer "B.Fab")
		)
		(fp_line
			(start 0.299974 0.150114)
			(end 0.299974 -0.150114)
			(stroke
				(width 0.1)
				(type default)
			)
			(layer "B.Fab")
		)
		(fp_line
			(start -0.299974 -0.150114)
			(end -0.299974 0.150114)
			(stroke
				(width 0.1)
				(type default)
			)
			(layer "B.Fab")
		)
		(fp_line
			(start 0.299974 -0.150114)
			(end -0.299974 -0.150114)
			(stroke
				(width 0.1)
				(type default)
			)
			(layer "B.Fab")
		)
		(pad "1" smd rect
			(at 0.2667 0 90)
			(size 0.3048 0.381)
			(layers "B.Cu" "B.Mask" "B.Paste")
			(net "P0V8_SERDES_VDDA_PEX2")
		)
		(pad "2" smd rect
			(at -0.2667 0 90)
			(size 0.3048 0.381)
			(layers "B.Cu" "B.Mask" "B.Paste")
			(net "GND")
		)
	)
	(footprint ""
		(layer "B.Cu")
		(at 344.49385 -217.187018 -90)
		(property "Reference" "C2055"
			(at 0 0 90)
			(layer "B.SilkS")
			(hide yes)
			(effects
				(font
					(size 1.27 1.27)
				)
				(justify mirror)
			)
		)
		(property "Value" ""
			(at 0 0 90)
			(layer "B.Fab")
			(effects
				(font
					(size 1.27 1.27)
				)
				(justify mirror)
			)
		)
		(duplicate_pad_numbers_are_jumpers no)
		(fp_line
			(start -0.69215 0.2921)
			(end 0.69215 0.2921)
			(stroke
				(width 0.1524)
				(type default)
			)
			(layer "B.SilkS")
		)
		(fp_line
			(start 0.69215 0.2921)
			(end 0.69215 -0.2921)
			(stroke
				(width 0.1524)
				(type default)
			)
			(layer "B.SilkS")
		)
		(fp_line
			(start -0.69215 -0.2921)
			(end -0.69215 0.2921)
			(stroke
				(width 0.1524)
				(type default)
			)
			(layer "B.SilkS")
		)
		(fp_line
			(start 0.69215 -0.2921)
			(end -0.69215 -0.2921)
			(stroke
				(width 0.1524)
				(type default)
			)
			(layer "B.SilkS")
		)
		(fp_line
			(start -0.51435 0.2794)
			(end 0.51435 0.2794)
			(stroke
				(width 0.1)
				(type default)
			)
			(layer "B.Fab")
		)
		(fp_line
			(start 0.51435 0.2794)
			(end 0.51435 -0.2794)
			(stroke
				(width 0.1)
				(type default)
			)
			(layer "B.Fab")
		)
		(fp_line
			(start -0.51435 -0.2794)
			(end -0.51435 0.2794)
			(stroke
				(width 0.1)
				(type default)
			)
			(layer "B.Fab")
		)
		(fp_line
			(start 0.51435 -0.2794)
			(end -0.51435 -0.2794)
			(stroke
				(width 0.1)
				(type default)
			)
			(layer "B.Fab")
		)
		(pad "1" smd circle
			(at 0.40005 0 90)
			(size 0 0)
			(layers "B.Cu" "B.Mask" "B.Paste")
			(net "P3V3_FPGA_VCCIO2")
		)
		(pad "2" smd circle
			(at -0.40005 0 90)
			(size 0 0)
			(layers "B.Cu" "B.Mask" "B.Paste")
			(net "GND")
		)
		(zone
			(layer "B.Cu")
			(hatch none 0.5)
			(connect_pads
				(clearance 0)
			)
			(min_thickness 0.25)
			(keepout
				(tracks not_allowed)
				(vias allowed)
				(pads allowed)
				(copperpour not_allowed)
				(footprints allowed)
			)
			(placement
				(enabled no)
				(sheetname "")
			)
			(fill
				(thermal_gap 0.5)
				(thermal_bridge_width 0.5)
				(island_removal_mode 0)
			)
			(polygon
				(pts
					(xy 344.40622 -216.996518) (xy 344.348054 -217.087958) (xy 344.348054 -217.287348) (xy 344.40622 -217.377518)
					(xy 344.58148 -217.377518) (xy 344.6399 -217.287348) (xy 344.6399 -217.087958) (xy 344.581734 -216.996518)
				)
			)
		)
	)
	(footprint ""
		(layer "B.Cu")
		(at 64.901318 -305.399948 -90)
		(property "Reference" "C2954"
			(at 0 0 90)
			(layer "B.SilkS")
			(hide yes)
			(effects
				(font
					(size 1.27 1.27)
				)
				(justify mirror)
			)
		)
		(property "Value" ""
			(at 0 0 90)
			(layer "B.Fab")
			(effects
				(font
					(size 1.27 1.27)
				)
				(justify mirror)
			)
		)
		(duplicate_pad_numbers_are_jumpers no)
		(fp_line
			(start -0.299974 0.150114)
			(end 0.299974 0.150114)
			(stroke
				(width 0.1)
				(type default)
			)
			(layer "B.Fab")
		)
		(fp_line
			(start 0.299974 0.150114)
			(end 0.299974 -0.150114)
			(stroke
				(width 0.1)
				(type default)
			)
			(layer "B.Fab")
		)
		(fp_line
			(start -0.299974 -0.150114)
			(end -0.299974 0.150114)
			(stroke
				(width 0.1)
				(type default)
			)
			(layer "B.Fab")
		)
		(fp_line
			(start 0.299974 -0.150114)
			(end -0.299974 -0.150114)
			(stroke
				(width 0.1)
				(type default)
			)
			(layer "B.Fab")
		)
		(pad "1" smd rect
			(at 0.2667 0 90)
			(size 0.3048 0.381)
			(layers "B.Cu" "B.Mask" "B.Paste")
			(net "P1V25_SERDES_VDDPLL_PEX0")
		)
		(pad "2" smd rect
			(at -0.2667 0 90)
			(size 0.3048 0.381)
			(layers "B.Cu" "B.Mask" "B.Paste")
			(net "GND")
		)
	)
)
